# T6G (Grand Teton) — schematic netlist excerpt (pin names and nets, part order shuffled) for the footprints in the layout excerpt that follows; sources: Cadence DE-HDL packaged netlist, KiCad conversion of 04192023_DAF0TMB3IC0_F0TG_MB_C_brd_V02_OCP.brd

J35  SCONN168_ME1016810202011  IO  pkg CON_F168S2H7D_P0-6W2-95_LUH  page 137
  GND_A1  = GND
  GND_A2  = GND
  GND_A3  = GND
  GND_A4  = GND
  GND_A5  = GND
  GND_A6  = GND
  SMCLK  = SMB_OCP_V3_2_3V3AUX_BUF_R_SCL
  SMDAT  = SMB_OCP_V3_2_3V3AUX_BUF_R_SDA
  \smrst#\  = RST_SMB_OCP_V3_2_N
  \prsnta#\  = OCP_V3_2_PRSNTA_R_N
  \perst1#\  = RST_PERST1_OCP_V3_2_N
  \prsntb2#\  = OCP_V3_2_PRSNT2_R_N
  GND_A13  = GND
  REFCLKN1  = CLK_100M_CPU1_CLK03_DN
  REFCLKP1  = CLK_100M_CPU1_CLK03_DP
  GND_A16  = GND
  PERN0  = P5E_CPU1_G1_RX_DN<0>
  PERP0  = P5E_CPU1_G1_RX_DP<0>
  GND_A19  = GND
  PERN1  = P5E_CPU1_G1_RX_DN<1>
  PERP1  = P5E_CPU1_G1_RX_DP<1>
  GND_A22  = GND
  PERN2  = P5E_CPU1_G1_RX_DN<2>
  PERP2  = P5E_CPU1_G1_RX_DP<2>
  GND_A25  = GND
  PERN3  = P5E_CPU1_G1_RX_DN<3>
  PERP3  = P5E_CPU1_G1_RX_DP<3>
  GND_A28  = GND
  GND_A29  = GND
  PERN4  = P5E_CPU1_G1_RX_DN<4>
  PERP4  = P5E_CPU1_G1_RX_DP<4>
  GND_A32  = GND
  PERN5  = P5E_CPU1_G1_RX_DN<5>
  PERP5  = P5E_CPU1_G1_RX_DP<5>
  GND_A35  = GND
  PERN6  = P5E_CPU1_G1_RX_DN<6>
  PERP6  = P5E_CPU1_G1_RX_DP<6>
  GND_A38  = GND
  PERN7  = P5E_CPU1_G1_RX_DN<7>
  PERP7  = P5E_CPU1_G1_RX_DP<7>
  GND_A41  = GND
  \prsntb1#\  = OCP_V3_2_PRSNT1_R_N
  GND_A43  = GND
  PERN8  = P5E_CPU1_G1_RX_DN<8>
  PERP8  = P5E_CPU1_G1_RX_DP<8>
  GND_A46  = GND
  PERN9  = P5E_CPU1_G1_RX_DN<9>
  PERP9  = P5E_CPU1_G1_RX_DP<9>
  GND_A49  = GND
  PERN10  = P5E_CPU1_G1_RX_DN<10>
  PERP10  = P5E_CPU1_G1_RX_DP<10>
  GND_A52  = GND
  PERN11  = P5E_CPU1_G1_RX_DN<11>
  PERP11  = P5E_CPU1_G1_RX_DP<11>
  GND_A55  = GND
  PERN12  = P5E_CPU1_G1_RX_DN<12>
  PERP12  = P5E_CPU1_G1_RX_DP<12>
  GND_A58  = GND
  PERN13  = P5E_CPU1_G1_RX_DN<13>
  PERP13  = P5E_CPU1_G1_RX_DP<13>
  GND_A61  = GND
  PERN14  = P5E_CPU1_G1_RX_DN<14>
  PERP14  = P5E_CPU1_G1_RX_DP<14>
  GND_A64  = GND
  PERN15  = P5E_CPU1_G1_RX_DN<15>
  PERP15  = P5E_CPU1_G1_RX_DP<15>
  GND_A67  = GND
  USB_DATN  = USB2_P10_DN
  USB_DATP  = USB2_P10_DP
  \pwrbrk0#\  = OCP_V3_2_PWRBRK_N
  \+12v_edge_b1\  = P12V_OCP_V3_2_R
  \+12v_edge_b2\  = P12V_OCP_V3_2_R
  \+12v_edge_b3\  = P12V_OCP_V3_2_R
  \+12v_edge_b4\  = P12V_OCP_V3_2_R
  \+12v_edge_b5\  = P12V_OCP_V3_2_R
  \+12v_edge_b6\  = P12V_OCP_V3_2_R
  \bif0#\  = OCP_V3_2_BIF0_R_N
  \bif1#\  = OCP_V3_2_BIF1_R_N
  \bif2#\  = OCP_V3_2_BIF2_R_N
  \perst0#\  = RST_PERST0_OCP_V3_2_N
  \+3.3v_edge\  = P3V3_OCP_V3_2
  AUX_PWR_EN  = OCP_V3_2_AUX_PWR_EN_R
  GND_B13  = GND
  REFCLKN0  = CLK_100M_CPU1_CLK02_DN
  REFCLKP0  = CLK_100M_CPU1_CLK02_DP
  GND_B16  = GND
  PETN0  = P5E_CPU1_G1_TX_C_DP<0>
  PETP0  = P5E_CPU1_G1_TX_C_DN<0>
  GND_B19  = GND
  PETN1  = P5E_CPU1_G1_TX_C_DP<1>
  PETP1  = P5E_CPU1_G1_TX_C_DN<1>
  GND_B22  = GND
  PETN2  = P5E_CPU1_G1_TX_C_DP<2>
  PETP2  = P5E_CPU1_G1_TX_C_DN<2>
  GND_B25  = GND
  PETN3  = P5E_CPU1_G1_TX_C_DP<3>
  PETP3  = P5E_CPU1_G1_TX_C_DN<3>
  GND_B28  = GND
  GND_B29  = GND
  PETN4  = P5E_CPU1_G1_TX_C_DP<4>
  PETP4  = P5E_CPU1_G1_TX_C_DN<4>
  GND_B32  = GND
  PETN5  = P5E_CPU1_G1_TX_C_DP<5>
  PETP5  = P5E_CPU1_G1_TX_C_DN<5>
  GND_B35  = GND
  PETN6  = P5E_CPU1_G1_TX_C_DP<6>
  PETP6  = P5E_CPU1_G1_TX_C_DN<6>
  GND_B38  = GND
  PETN7  = P5E_CPU1_G1_TX_C_DP<7>
  PETP7  = P5E_CPU1_G1_TX_C_DN<7>
  GND_B41  = GND
  \prsntb0#\  = OCP_V3_2_PRSNT0_R_N
  GND_B43  = GND
  PETN8  = P5E_CPU1_G1_TX_C_DP<8>
  PETP8  = P5E_CPU1_G1_TX_C_DN<8>
  GND_B46  = GND
  PETN9  = P5E_CPU1_G1_TX_C_DP<9>
  PETP9  = P5E_CPU1_G1_TX_C_DN<9>
  GND_B49  = GND
  PETN10  = P5E_CPU1_G1_TX_C_DP<10>
  PETP10  = P5E_CPU1_G1_TX_C_DN<10>
  GND_B52  = GND
  PETN11  = P5E_CPU1_G1_TX_C_DP<11>
  PETP11  = P5E_CPU1_G1_TX_C_DN<11>
  GND_B55  = GND
  PETN12  = P5E_CPU1_G1_TX_C_DP<12>
  PETP12  = P5E_CPU1_G1_TX_C_DN<12>
  GND_B58  = GND
  PETN13  = P5E_CPU1_G1_TX_C_DP<13>
  PETP13  = P5E_CPU1_G1_TX_C_DN<13>
  GND_B61  = GND
  PETN14  = P5E_CPU1_G1_TX_C_DP<14>
  PETP14  = P5E_CPU1_G1_TX_C_DN<14>
  GND_B64  = GND
  PETN15  = P5E_CPU1_G1_TX_C_DP<15>
  PETP15  = P5E_CPU1_G1_TX_C_DN<15>
  GND_B67  = GND
  RFU1_NC_B68  = TP_OCP_V3_2_B68
  RFU1_NC_B69  = TP_OCP_V3_2_B69
  \prsntb3#\  = OCP_V3_2_PRSNT3_R_N
  G1  = GND
  G2  = GND
  G3  = GND
  G4  = GND
  G5  = GND
  \perst2#\  = RST_PERST2_OCP_V3_2_N
  \perst3#\  = RST_PERST3_OCP_V3_2_N
  \wake#\  = IRQ_LVC3_OCP_V3_2_WAKE_N
  RBT_ARB_IN  = OCP_V3_2_ISO1_RBT_ARB_IN
  RBT_ARB_OUT  = OCP_V3_2_ISO2_RBT_ARB_OUT
  SLOT_ID1  = OCP_V3_2_ID1
  RBT_TX_EN  = NCSI_OCP_V3_2_TX_EN
  RBT_TXD1  = NCSI_OCP_V3_2_TXD1
  RBT_TXD0  = NCSI_OCP_V3_2_TXD0
  GND_OA10  = GND
  REFCLKN3  = CLK_100M_CPU1_CLK05_DN
  REFCLKP3  = CLK_100M_CPU1_CLK05_DP
  GND_OA13  = GND
  RBT_CLK_IN  = CLK_50M_NCSI_OCP_V3_2_ISO
  NIC_PWR_GOOD  = FM_OCP_V3_2_PWR_GOOD
  MAIN_PWR_EN  = OCP_V3_2_MAIN_PWR_EN_R
  \ld#\  = SGPIO_OCP_V3_2_LD_N
  DATA_IN  = SGPIO_OCP_V3_2_DATAIN
  DATA_OUT  = SGPIO_OCP_V3_2_DATAOUT
  CLK  = SGPIO_OCP_V3_2_CLK
  SLOT_ID0  = OCP_V3_2_ID0
  RBT_RXD1  = NCSI_OCP_V3_2_RXD1
  RBT_RXD0  = NCSI_OCP_V3_2_RXD0
  GND_OB10  = GND
  REFCLKN2  = CLK_100M_CPU1_CLK04_DN
  REFCLKP2  = CLK_100M_CPU1_CLK04_DP
  GND_OB13  = GND
  RBT_CRS_DV  = NCSI_OCP_V3_2_CRS_DV

(kicad_pcb
	(version 20260206)
	(generator "pcbnew")
	(generator_version "10.0")
	(general
		(thickness 1.6)
		(legacy_teardrops no)
	)
	(paper "A4")
	(title_block
		(title "04192023_DAF0TMB3IC0_F0TG_MB_C_brd_V02_OCP.brd")
		(comment 1 "Grand Teton / footprint 4922 of 8354 (J35), pads 46-89 of 175")
	)
	(layers
		(0 "F.Cu" signal "TOP")
		(4 "In1.Cu" signal "GND")
		(6 "In2.Cu" signal "IN1")
		(8 "In3.Cu" signal "GND1")
		(10 "In4.Cu" signal "IN2")
		(12 "In5.Cu" signal "GND2")
		(14 "In6.Cu" signal "IN3")
		(16 "In7.Cu" signal "GND3")
		(18 "In8.Cu" signal "VCC")
		(20 "In9.Cu" signal "VCC1")
		(22 "In10.Cu" signal "GND4")
		(24 "In11.Cu" signal "IN4")
		(26 "In12.Cu" signal "GND5")
		(28 "In13.Cu" signal "IN5")
		(30 "In14.Cu" signal "GND6")
		(32 "In15.Cu" signal "IN6")
		(34 "In16.Cu" signal "GND7")
		(2 "B.Cu" signal "BOTTOM")
		(9 "F.Adhes" user "F.Adhesive")
		(11 "B.Adhes" user "B.Adhesive")
		(13 "F.Paste" user "Package Geometry/Pastemask Top")
		(15 "B.Paste" user "Package Geometry/Pastemask Bottom")
		(5 "F.SilkS" user "Ref Des/Silkscreen Top")
		(7 "B.SilkS" user "Ref Des/Silkscreen Bottom")
		(1 "F.Mask" user "Board Geometry/Soldermask Top")
		(3 "B.Mask" user "Board Geometry/Soldermask Bottom")
		(17 "Dwgs.User" user "User.Drawings")
		(19 "Cmts.User" user "User.Comments")
		(21 "Eco1.User" user "User.Eco1")
		(23 "Eco2.User" user "User.Eco2")
		(25 "Edge.Cuts" user "Board Geometry/Outline")
		(27 "Margin" user)
		(31 "F.CrtYd" user "Package Geometry/Place Bound Top")
		(29 "B.CrtYd" user "Package Geometry/Place Bound Bottom")
		(35 "F.Fab" user "Ref Des/Assembly Top")
		(33 "B.Fab" user "Ref Des/Assembly Bottom")
	)
	(footprint ""
		(layer "F.Cu")
		(at 47.401988 -5.569966 -90)
		(property "Reference" "J35"
			(at -8.0772 -20.659598 0)
			(unlocked yes)
			(layer "F.SilkS")
			(effects
				(font
					(size 0.7874 0.5842)
					(thickness 0.1524)
				)
				(justify left)
			)
		)
		(property "Value" ""
			(at 0 0 270)
			(layer "F.Fab")
			(effects
				(font
					(size 1.27 1.27)
				)
			)
		)
		(duplicate_pad_numbers_are_jumpers no)
		(pad "A44" smd rect
			(at -2.750058 15.055088 180)
			(size 0.381 1.4478)
			(layers "F.Cu" "F.Mask" "F.Paste")
			(net "P5E_CPU1_G1_RX_DN<8>")
		)
		(pad "A45" smd rect
			(at -2.750058 15.655036 180)
			(size 0.381 1.4478)
			(layers "F.Cu" "F.Mask" "F.Paste")
			(net "P5E_CPU1_G1_RX_DP<8>")
		)
		(pad "A46" smd rect
			(at -2.750058 16.254984 180)
			(size 0.381 1.4478)
			(layers "F.Cu" "F.Mask" "F.Paste")
			(net "GND")
		)
		(pad "A47" smd rect
			(at -2.750058 16.854932 180)
			(size 0.381 1.4478)
			(layers "F.Cu" "F.Mask" "F.Paste")
			(net "P5E_CPU1_G1_RX_DN<9>")
		)
		(pad "A48" smd rect
			(at -2.750058 17.45488 180)
			(size 0.381 1.4478)
			(layers "F.Cu" "F.Mask" "F.Paste")
			(net "P5E_CPU1_G1_RX_DP<9>")
		)
		(pad "A49" smd rect
			(at -2.750058 18.055082 180)
			(size 0.381 1.4478)
			(layers "F.Cu" "F.Mask" "F.Paste")
			(net "GND")
		)
		(pad "A50" smd rect
			(at -2.750058 18.65503 180)
			(size 0.381 1.4478)
			(layers "F.Cu" "F.Mask" "F.Paste")
			(net "P5E_CPU1_G1_RX_DN<10>")
		)
		(pad "A51" smd rect
			(at -2.750058 19.254978 180)
			(size 0.381 1.4478)
			(layers "F.Cu" "F.Mask" "F.Paste")
			(net "P5E_CPU1_G1_RX_DP<10>")
		)
		(pad "A52" smd rect
			(at -2.750058 19.854926 180)
			(size 0.381 1.4478)
			(layers "F.Cu" "F.Mask" "F.Paste")
			(net "GND")
		)
		(pad "A53" smd rect
			(at -2.750058 20.455128 180)
			(size 0.381 1.4478)
			(layers "F.Cu" "F.Mask" "F.Paste")
			(net "P5E_CPU1_G1_RX_DN<11>")
		)
		(pad "A54" smd rect
			(at -2.750058 21.055076 180)
			(size 0.381 1.4478)
			(layers "F.Cu" "F.Mask" "F.Paste")
			(net "P5E_CPU1_G1_RX_DP<11>")
		)
		(pad "A55" smd rect
			(at -2.750058 21.655024 180)
			(size 0.381 1.4478)
			(layers "F.Cu" "F.Mask" "F.Paste")
			(net "GND")
		)
		(pad "A56" smd rect
			(at -2.750058 22.254972 180)
			(size 0.381 1.4478)
			(layers "F.Cu" "F.Mask" "F.Paste")
			(net "P5E_CPU1_G1_RX_DN<12>")
		)
		(pad "A57" smd rect
			(at -2.750058 22.85492 180)
			(size 0.381 1.4478)
			(layers "F.Cu" "F.Mask" "F.Paste")
			(net "P5E_CPU1_G1_RX_DP<12>")
		)
		(pad "A58" smd rect
			(at -2.750058 23.455122 180)
			(size 0.381 1.4478)
			(layers "F.Cu" "F.Mask" "F.Paste")
			(net "GND")
		)
		(pad "A59" smd rect
			(at -2.750058 24.05507 180)
			(size 0.381 1.4478)
			(layers "F.Cu" "F.Mask" "F.Paste")
			(net "P5E_CPU1_G1_RX_DN<13>")
		)
		(pad "A60" smd rect
			(at -2.750058 24.655018 180)
			(size 0.381 1.4478)
			(layers "F.Cu" "F.Mask" "F.Paste")
			(net "P5E_CPU1_G1_RX_DP<13>")
		)
		(pad "A61" smd rect
			(at -2.750058 25.254966 180)
			(size 0.381 1.4478)
			(layers "F.Cu" "F.Mask" "F.Paste")
			(net "GND")
		)
		(pad "A62" smd rect
			(at -2.750058 25.854914 180)
			(size 0.381 1.4478)
			(layers "F.Cu" "F.Mask" "F.Paste")
			(net "P5E_CPU1_G1_RX_DN<14>")
		)
		(pad "A63" smd rect
			(at -2.750058 26.455116 180)
			(size 0.381 1.4478)
			(layers "F.Cu" "F.Mask" "F.Paste")
			(net "P5E_CPU1_G1_RX_DP<14>")
		)
		(pad "A64" smd rect
			(at -2.750058 27.055064 180)
			(size 0.381 1.4478)
			(layers "F.Cu" "F.Mask" "F.Paste")
			(net "GND")
		)
		(pad "A65" smd rect
			(at -2.750058 27.655012 180)
			(size 0.381 1.4478)
			(layers "F.Cu" "F.Mask" "F.Paste")
			(net "P5E_CPU1_G1_RX_DN<15>")
		)
		(pad "A66" smd rect
			(at -2.750058 28.25496 180)
			(size 0.381 1.4478)
			(layers "F.Cu" "F.Mask" "F.Paste")
			(net "P5E_CPU1_G1_RX_DP<15>")
		)
		(pad "A67" smd rect
			(at -2.750058 28.854908 180)
			(size 0.381 1.4478)
			(layers "F.Cu" "F.Mask" "F.Paste")
			(net "GND")
		)
		(pad "A68" smd rect
			(at -2.750058 29.45511 180)
			(size 0.381 1.4478)
			(layers "F.Cu" "F.Mask" "F.Paste")
			(net "USB2_P10_DN")
		)
		(pad "A69" smd rect
			(at -2.750058 30.055058 180)
			(size 0.381 1.4478)
			(layers "F.Cu" "F.Mask" "F.Paste")
			(net "USB2_P10_DP")
		)
		(pad "A70" smd rect
			(at -2.750058 30.655006 180)
			(size 0.381 1.4478)
			(layers "F.Cu" "F.Mask" "F.Paste")
			(net "OCP_V3_2_PWRBRK_N")
		)
		(pad "B1" smd rect
			(at -5.700014 -18.465038 180)
			(size 0.381 1.4478)
			(layers "F.Cu" "F.Mask" "F.Paste")
			(net "P12V_OCP_V3_2_R")
		)
		(pad "B2" smd rect
			(at -5.700014 -17.86509 180)
			(size 0.381 1.4478)
			(layers "F.Cu" "F.Mask" "F.Paste")
			(net "P12V_OCP_V3_2_R")
		)
		(pad "B3" smd rect
			(at -5.700014 -17.264888 180)
			(size 0.381 1.4478)
			(layers "F.Cu" "F.Mask" "F.Paste")
			(net "P12V_OCP_V3_2_R")
		)
		(pad "B4" smd rect
			(at -5.700014 -16.66494 180)
			(size 0.381 1.4478)
			(layers "F.Cu" "F.Mask" "F.Paste")
			(net "P12V_OCP_V3_2_R")
		)
		(pad "B5" smd rect
			(at -5.700014 -16.064992 180)
			(size 0.381 1.4478)
			(layers "F.Cu" "F.Mask" "F.Paste")
			(net "P12V_OCP_V3_2_R")
		)
		(pad "B6" smd rect
			(at -5.700014 -15.465044 180)
			(size 0.381 1.4478)
			(layers "F.Cu" "F.Mask" "F.Paste")
			(net "P12V_OCP_V3_2_R")
		)
		(pad "B7" smd rect
			(at -5.700014 -14.865096 180)
			(size 0.381 1.4478)
			(layers "F.Cu" "F.Mask" "F.Paste")
			(net "OCP_V3_2_BIF0_R_N")
		)
		(pad "B8" smd rect
			(at -5.700014 -14.264894 180)
			(size 0.381 1.4478)
			(layers "F.Cu" "F.Mask" "F.Paste")
			(net "OCP_V3_2_BIF1_R_N")
		)
		(pad "B9" smd rect
			(at -5.700014 -13.664946 180)
			(size 0.381 1.4478)
			(layers "F.Cu" "F.Mask" "F.Paste")
			(net "OCP_V3_2_BIF2_R_N")
		)
		(pad "B10" smd rect
			(at -5.700014 -13.064998 180)
			(size 0.381 1.4478)
			(layers "F.Cu" "F.Mask" "F.Paste")
			(net "RST_PERST0_OCP_V3_2_N")
		)
		(pad "B11" smd rect
			(at -5.700014 -12.46505 180)
			(size 0.381 1.4478)
			(layers "F.Cu" "F.Mask" "F.Paste")
			(net "P3V3_OCP_V3_2")
		)
		(pad "B12" smd rect
			(at -5.700014 -11.865102 180)
			(size 0.381 1.4478)
			(layers "F.Cu" "F.Mask" "F.Paste")
			(net "OCP_V3_2_AUX_PWR_EN_R")
		)
		(pad "B13" smd rect
			(at -5.700014 -11.2649 180)
			(size 0.381 1.4478)
			(layers "F.Cu" "F.Mask" "F.Paste")
			(net "GND")
		)
		(pad "B14" smd rect
			(at -5.700014 -10.664952 180)
			(size 0.381 1.4478)
			(layers "F.Cu" "F.Mask" "F.Paste")
			(net "CLK_100M_CPU1_CLK02_DN")
		)
		(pad "B15" smd rect
			(at -5.700014 -10.065004 180)
			(size 0.381 1.4478)
			(layers "F.Cu" "F.Mask" "F.Paste")
			(net "CLK_100M_CPU1_CLK02_DP")
		)
		(pad "B16" smd rect
			(at -5.700014 -9.465056 180)
			(size 0.381 1.4478)
			(layers "F.Cu" "F.Mask" "F.Paste")
			(net "GND")
		)
		(pad "B17" smd rect
			(at -5.700014 -8.865108 180)
			(size 0.381 1.4478)
			(layers "F.Cu" "F.Mask" "F.Paste")
			(net "P5E_CPU1_G1_TX_C_DP<0>")
		)
	)
)
